(kicad_pcb
	(version 20260206)
	(generator "pcbnew")
	(generator_version "10.0")
	(general
		(thickness 1.6)
		(legacy_teardrops no)
	)
	(paper "A4")
	(title_block
		(title "03242023_DA0F0TMBIJ0_F0T_Motherboard_J_brd_V01_OCP.brd")
		(comment 1 "Grand Teton / footprints 2415-2421 of 6105")
	)
	(layers
		(0 "F.Cu" signal "TOP")
		(4 "In1.Cu" signal "GND")
		(6 "In2.Cu" signal "IN1")
		(8 "In3.Cu" signal "GND1")
		(10 "In4.Cu" signal "IN2")
		(12 "In5.Cu" signal "GND2")
		(14 "In6.Cu" signal "IN3")
		(16 "In7.Cu" signal "GND3")
		(18 "In8.Cu" signal "VCC")
		(20 "In9.Cu" signal "VCC1")
		(22 "In10.Cu" signal "GND4")
		(24 "In11.Cu" signal "IN4")
		(26 "In12.Cu" signal "GND5")
		(28 "In13.Cu" signal "IN5")
		(30 "In14.Cu" signal "GND6")
		(32 "In15.Cu" signal "IN6")
		(34 "In16.Cu" signal "GND7")
		(2 "B.Cu" signal "BOTTOM")
		(9 "F.Adhes" user "F.Adhesive")
		(11 "B.Adhes" user "B.Adhesive")
		(13 "F.Paste" user "Package Geometry/Pastemask Top")
		(15 "B.Paste" user "Package Geometry/Pastemask Bottom")
		(5 "F.SilkS" user "Ref Des/Silkscreen Top")
		(7 "B.SilkS" user "Ref Des/Silkscreen Bottom")
		(1 "F.Mask" user "Board Geometry/Soldermask Top")
		(3 "B.Mask" user "Board Geometry/Soldermask Bottom")
		(17 "Dwgs.User" user "User.Drawings")
		(19 "Cmts.User" user "User.Comments")
		(21 "Eco1.User" user "User.Eco1")
		(23 "Eco2.User" user "User.Eco2")
		(25 "Edge.Cuts" user "Board Geometry/Outline")
		(27 "Margin" user)
		(31 "F.CrtYd" user "Package Geometry/Place Bound Top")
		(29 "B.CrtYd" user "Package Geometry/Place Bound Bottom")
		(35 "F.Fab" user "Ref Des/Assembly Top")
		(33 "B.Fab" user "Ref Des/Assembly Bottom")
	)
	(footprint ""
		(layer "F.Cu")
		(at 254.147828 -70.440296 -90)
		(property "Reference" "PC1216"
			(at 0 0 270)
			(layer "F.SilkS")
			(hide yes)
			(effects
				(font
					(size 1.27 1.27)
				)
			)
		)
		(property "Value" ""
			(at 0 0 270)
			(layer "F.Fab")
			(effects
				(font
					(size 1.27 1.27)
				)
			)
		)
		(duplicate_pad_numbers_are_jumpers no)
		(fp_line
			(start -1.524 0.762)
			(end -1.524 -0.762)
			(stroke
				(width 0.1524)
				(type default)
			)
			(layer "F.SilkS")
		)
		(fp_line
			(start 1.524 0.762)
			(end -1.524 0.762)
			(stroke
				(width 0.1524)
				(type default)
			)
			(layer "F.SilkS")
		)
		(fp_line
			(start -1.524 -0.762)
			(end 1.524 -0.762)
			(stroke
				(width 0.1524)
				(type default)
			)
			(layer "F.SilkS")
		)
		(fp_line
			(start 1.524 -0.762)
			(end 1.524 0.762)
			(stroke
				(width 0.1524)
				(type default)
			)
			(layer "F.SilkS")
		)
		(fp_line
			(start -1.1049 0.724916)
			(end 1.1049 0.724916)
			(stroke
				(width 0.1)
				(type default)
			)
			(layer "F.Fab")
		)
		(fp_line
			(start 1.1049 0.724916)
			(end 1.1049 -0.724916)
			(stroke
				(width 0.1)
				(type default)
			)
			(layer "F.Fab")
		)
		(fp_line
			(start -1.1049 -0.724916)
			(end -1.1049 0.724916)
			(stroke
				(width 0.1)
				(type default)
			)
			(layer "F.Fab")
		)
		(fp_line
			(start 1.1049 -0.724916)
			(end -1.1049 -0.724916)
			(stroke
				(width 0.1)
				(type default)
			)
			(layer "F.Fab")
		)
		(pad "1" smd rect
			(at -0.889 0 90)
			(size 1.016 1.27)
			(layers "F.Cu" "F.Mask" "F.Paste")
			(net "SW_P12V_AUX_P1V05_PCH_AUX_FLT")
		)
		(pad "2" smd rect
			(at 0.889 0 90)
			(size 1.016 1.27)
			(layers "F.Cu" "F.Mask" "F.Paste")
			(net "GND")
		)
	)
	(footprint ""
		(layer "F.Cu")
		(at 423.68216 -143.675608 90)
		(property "Reference" "PR4224"
			(at 0 0 90)
			(layer "F.SilkS")
			(hide yes)
			(effects
				(font
					(size 1.27 1.27)
				)
			)
		)
		(property "Value" ""
			(at 0 0 90)
			(layer "F.Fab")
			(effects
				(font
					(size 1.27 1.27)
				)
			)
		)
		(duplicate_pad_numbers_are_jumpers no)
		(fp_line
			(start 0.7874 -0.4064)
			(end 0.7874 0.4064)
			(stroke
				(width 0.1524)
				(type default)
			)
			(layer "F.SilkS")
		)
		(fp_line
			(start -0.7874 -0.4064)
			(end 0.7874 -0.4064)
			(stroke
				(width 0.1524)
				(type default)
			)
			(layer "F.SilkS")
		)
		(fp_line
			(start 0.7874 0.4064)
			(end -0.7874 0.4064)
			(stroke
				(width 0.1524)
				(type default)
			)
			(layer "F.SilkS")
		)
		(fp_line
			(start -0.7874 0.4064)
			(end -0.7874 -0.4064)
			(stroke
				(width 0.1524)
				(type default)
			)
			(layer "F.SilkS")
		)
		(fp_line
			(start -0.12065 -0.305054)
			(end -0.12065 -0.2794)
			(stroke
				(width 0.1)
				(type default)
			)
			(layer "F.Fab")
		)
		(fp_line
			(start -0.67945 -0.305054)
			(end -0.12065 -0.305054)
			(stroke
				(width 0.1)
				(type default)
			)
			(layer "F.Fab")
		)
		(fp_line
			(start 0.67945 -0.3048)
			(end 0.67945 0.3048)
			(stroke
				(width 0.1)
				(type default)
			)
			(layer "F.Fab")
		)
		(fp_line
			(start 0.12065 -0.3048)
			(end 0.67945 -0.3048)
			(stroke
				(width 0.1)
				(type default)
			)
			(layer "F.Fab")
		)
		(fp_line
			(start 0.12065 -0.2794)
			(end 0.12065 -0.3048)
			(stroke
				(width 0.1)
				(type default)
			)
			(layer "F.Fab")
		)
		(fp_line
			(start -0.12065 -0.2794)
			(end 0.12065 -0.2794)
			(stroke
				(width 0.1)
				(type default)
			)
			(layer "F.Fab")
		)
		(fp_line
			(start 0.120396 0.2794)
			(end -0.12065 0.2794)
			(stroke
				(width 0.1)
				(type default)
			)
			(layer "F.Fab")
		)
		(fp_line
			(start -0.12065 0.2794)
			(end -0.12065 0.3048)
			(stroke
				(width 0.1)
				(type default)
			)
			(layer "F.Fab")
		)
		(fp_line
			(start 0.67945 0.3048)
			(end 0.120396 0.3048)
			(stroke
				(width 0.1)
				(type default)
			)
			(layer "F.Fab")
		)
		(fp_line
			(start 0.120396 0.3048)
			(end 0.120396 0.2794)
			(stroke
				(width 0.1)
				(type default)
			)
			(layer "F.Fab")
		)
		(fp_line
			(start -0.12065 0.3048)
			(end -0.67945 0.3048)
			(stroke
				(width 0.1)
				(type default)
			)
			(layer "F.Fab")
		)
		(fp_line
			(start -0.67945 0.3048)
			(end -0.67945 -0.305054)
			(stroke
				(width 0.1)
				(type default)
			)
			(layer "F.Fab")
		)
		(pad "1" smd circle
			(at -0.40005 0 90)
			(size 0 0)
			(layers "F.Cu" "F.Mask" "F.Paste")
			(net "NC_PVCCINFAON_CPU0_ACSP6")
		)
		(pad "2" smd circle
			(at 0.40005 0 90)
			(size 0 0)
			(layers "F.Cu" "F.Mask" "F.Paste")
			(net "GND")
		)
	)
	(footprint ""
		(layer "F.Cu")
		(at 163.50488 -435.447948 180)
		(property "Reference" "R3452"
			(at 0 0 180)
			(layer "F.SilkS")
			(hide yes)
			(effects
				(font
					(size 1.27 1.27)
				)
			)
		)
		(property "Value" ""
			(at 0 0 180)
			(layer "F.Fab")
			(effects
				(font
					(size 1.27 1.27)
				)
			)
		)
		(duplicate_pad_numbers_are_jumpers no)
		(fp_line
			(start 0.7874 0.4064)
			(end -0.7874 0.4064)
			(stroke
				(width 0.1524)
				(type default)
			)
			(layer "F.SilkS")
		)
		(fp_line
			(start 0.7874 -0.4064)
			(end 0.7874 0.4064)
			(stroke
				(width 0.1524)
				(type default)
			)
			(layer "F.SilkS")
		)
		(fp_line
			(start -0.7874 0.4064)
			(end -0.7874 -0.4064)
			(stroke
				(width 0.1524)
				(type default)
			)
			(layer "F.SilkS")
		)
		(fp_line
			(start -0.7874 -0.4064)
			(end 0.7874 -0.4064)
			(stroke
				(width 0.1524)
				(type default)
			)
			(layer "F.SilkS")
		)
		(fp_line
			(start 0.67945 0.3048)
			(end 0.120396 0.3048)
			(stroke
				(width 0.1)
				(type default)
			)
			(layer "F.Fab")
		)
		(fp_line
			(start 0.67945 -0.3048)
			(end 0.67945 0.3048)
			(stroke
				(width 0.1)
				(type default)
			)
			(layer "F.Fab")
		)
		(fp_line
			(start 0.12065 -0.2794)
			(end 0.12065 -0.3048)
			(stroke
				(width 0.1)
				(type default)
			)
			(layer "F.Fab")
		)
		(fp_line
			(start 0.12065 -0.3048)
			(end 0.67945 -0.3048)
			(stroke
				(width 0.1)
				(type default)
			)
			(layer "F.Fab")
		)
		(fp_line
			(start 0.120396 0.3048)
			(end 0.120396 0.2794)
			(stroke
				(width 0.1)
				(type default)
			)
			(layer "F.Fab")
		)
		(fp_line
			(start 0.120396 0.2794)
			(end -0.12065 0.2794)
			(stroke
				(width 0.1)
				(type default)
			)
			(layer "F.Fab")
		)
		(fp_line
			(start -0.12065 0.3048)
			(end -0.67945 0.3048)
			(stroke
				(width 0.1)
				(type default)
			)
			(layer "F.Fab")
		)
		(fp_line
			(start -0.12065 0.2794)
			(end -0.12065 0.3048)
			(stroke
				(width 0.1)
				(type default)
			)
			(layer "F.Fab")
		)
		(fp_line
			(start -0.12065 -0.2794)
			(end 0.12065 -0.2794)
			(stroke
				(width 0.1)
				(type default)
			)
			(layer "F.Fab")
		)
		(fp_line
			(start -0.12065 -0.305054)
			(end -0.12065 -0.2794)
			(stroke
				(width 0.1)
				(type default)
			)
			(layer "F.Fab")
		)
		(fp_line
			(start -0.67945 0.3048)
			(end -0.67945 -0.305054)
			(stroke
				(width 0.1)
				(type default)
			)
			(layer "F.Fab")
		)
		(fp_line
			(start -0.67945 -0.305054)
			(end -0.12065 -0.305054)
			(stroke
				(width 0.1)
				(type default)
			)
			(layer "F.Fab")
		)
		(pad "1" smd circle
			(at -0.40005 0 180)
			(size 0 0)
			(layers "F.Cu" "F.Mask" "F.Paste")
			(net "GPU_BASE_STBY_EN")
		)
		(pad "2" smd circle
			(at 0.40005 0 180)
			(size 0 0)
			(layers "F.Cu" "F.Mask" "F.Paste")
			(net "GND")
		)
	)
	(footprint ""
		(layer "F.Cu")
		(at 68.961 -34.788348)
		(property "Reference" "R3591"
			(at 0 0 0)
			(layer "F.SilkS")
			(hide yes)
			(effects
				(font
					(size 1.27 1.27)
				)
			)
		)
		(property "Value" ""
			(at 0 0 0)
			(layer "F.Fab")
			(effects
				(font
					(size 1.27 1.27)
				)
			)
		)
		(duplicate_pad_numbers_are_jumpers no)
		(fp_line
			(start -0.7874 -0.4064)
			(end 0.7874 -0.4064)
			(stroke
				(width 0.1524)
				(type default)
			)
			(layer "F.SilkS")
		)
		(fp_line
			(start -0.7874 0.4064)
			(end -0.7874 -0.4064)
			(stroke
				(width 0.1524)
				(type default)
			)
			(layer "F.SilkS")
		)
		(fp_line
			(start 0.7874 -0.4064)
			(end 0.7874 0.4064)
			(stroke
				(width 0.1524)
				(type default)
			)
			(layer "F.SilkS")
		)
		(fp_line
			(start 0.7874 0.4064)
			(end -0.7874 0.4064)
			(stroke
				(width 0.1524)
				(type default)
			)
			(layer "F.SilkS")
		)
		(fp_line
			(start -0.67945 -0.305054)
			(end -0.12065 -0.305054)
			(stroke
				(width 0.1)
				(type default)
			)
			(layer "F.Fab")
		)
		(fp_line
			(start -0.67945 0.3048)
			(end -0.67945 -0.305054)
			(stroke
				(width 0.1)
				(type default)
			)
			(layer "F.Fab")
		)
		(fp_line
			(start -0.12065 -0.305054)
			(end -0.12065 -0.2794)
			(stroke
				(width 0.1)
				(type default)
			)
			(layer "F.Fab")
		)
		(fp_line
			(start -0.12065 -0.2794)
			(end 0.12065 -0.2794)
			(stroke
				(width 0.1)
				(type default)
			)
			(layer "F.Fab")
		)
		(fp_line
			(start -0.12065 0.2794)
			(end -0.12065 0.3048)
			(stroke
				(width 0.1)
				(type default)
			)
			(layer "F.Fab")
		)
		(fp_line
			(start -0.12065 0.3048)
			(end -0.67945 0.3048)
			(stroke
				(width 0.1)
				(type default)
			)
			(layer "F.Fab")
		)
		(fp_line
			(start 0.120396 0.2794)
			(end -0.12065 0.2794)
			(stroke
				(width 0.1)
				(type default)
			)
			(layer "F.Fab")
		)
		(fp_line
			(start 0.120396 0.3048)
			(end 0.120396 0.2794)
			(stroke
				(width 0.1)
				(type default)
			)
			(layer "F.Fab")
		)
		(fp_line
			(start 0.12065 -0.3048)
			(end 0.67945 -0.3048)
			(stroke
				(width 0.1)
				(type default)
			)
			(layer "F.Fab")
		)
		(fp_line
			(start 0.12065 -0.2794)
			(end 0.12065 -0.3048)
			(stroke
				(width 0.1)
				(type default)
			)
			(layer "F.Fab")
		)
		(fp_line
			(start 0.67945 -0.3048)
			(end 0.67945 0.3048)
			(stroke
				(width 0.1)
				(type default)
			)
			(layer "F.Fab")
		)
		(fp_line
			(start 0.67945 0.3048)
			(end 0.120396 0.3048)
			(stroke
				(width 0.1)
				(type default)
			)
			(layer "F.Fab")
		)
		(pad "1" smd circle
			(at -0.40005 0)
			(size 0 0)
			(layers "F.Cu" "F.Mask" "F.Paste")
			(net "SMB_INA230_3V3AUX_SDA")
		)
		(pad "2" smd circle
			(at 0.40005 0)
			(size 0 0)
			(layers "F.Cu" "F.Mask" "F.Paste")
			(net "SMB_INA230_3_3V3AUX_SDA_R")
		)
	)
	(footprint ""
		(layer "F.Cu")
		(at 52.363878 -408.517344 -90)
		(property "Reference" "C707"
			(at 0 0 270)
			(layer "F.SilkS")
			(hide yes)
			(effects
				(font
					(size 1.27 1.27)
				)
			)
		)
		(property "Value" ""
			(at 0 0 270)
			(layer "F.Fab")
			(effects
				(font
					(size 1.27 1.27)
				)
			)
		)
		(duplicate_pad_numbers_are_jumpers no)
		(fp_line
			(start -0.299974 0.150114)
			(end -0.299974 -0.150114)
			(stroke
				(width 0.1)
				(type default)
			)
			(layer "F.Fab")
		)
		(fp_line
			(start 0.299974 0.150114)
			(end -0.299974 0.150114)
			(stroke
				(width 0.1)
				(type default)
			)
			(layer "F.Fab")
		)
		(fp_line
			(start -0.299974 -0.150114)
			(end 0.299974 -0.150114)
			(stroke
				(width 0.1)
				(type default)
			)
			(layer "F.Fab")
		)
		(fp_line
			(start 0.299974 -0.150114)
			(end 0.299974 0.150114)
			(stroke
				(width 0.1)
				(type default)
			)
			(layer "F.Fab")
		)
		(pad "1" smd rect
			(at -0.2667 0 270)
			(size 0.3048 0.381)
			(layers "F.Cu" "F.Mask" "F.Paste")
			(net "P5E_CPU1_PE4_TX_C_DP<1>")
		)
		(pad "2" smd rect
			(at 0.2667 0 270)
			(size 0.3048 0.381)
			(layers "F.Cu" "F.Mask" "F.Paste")
			(net "P5E_CPU1_PE4_TX_DP<1>")
		)
	)
	(footprint ""
		(layer "F.Cu")
		(at 134.42188 -96.357948 -90)
		(property "Reference" "Q142"
			(at -0.035052 -2.38379 90)
			(unlocked yes)
			(layer "F.SilkS")
			(effects
				(font
					(size 0.7874 0.5842)
					(thickness 0.1524)
				)
			)
		)
		(property "Value" ""
			(at 0 0 270)
			(layer "F.Fab")
			(effects
				(font
					(size 1.27 1.27)
				)
			)
		)
		(duplicate_pad_numbers_are_jumpers no)
		(fp_line
			(start -1.376172 1.199896)
			(end -1.376172 -1.199896)
			(stroke
				(width 0.1524)
				(type default)
			)
			(layer "F.SilkS")
		)
		(fp_line
			(start 1.376172 1.199896)
			(end -1.376172 1.199896)
			(stroke
				(width 0.1524)
				(type default)
			)
			(layer "F.SilkS")
		)
		(fp_line
			(start 0 -0.762)
			(end 0.508 -1.199896)
			(stroke
				(width 0.1524)
				(type default)
			)
			(layer "F.SilkS")
		)
		(fp_line
			(start -1.376172 -1.199896)
			(end -0.508 -1.199896)
			(stroke
				(width 0.1524)
				(type default)
			)
			(layer "F.SilkS")
		)
		(fp_line
			(start -0.508 -1.199896)
			(end 0 -0.762)
			(stroke
				(width 0.1524)
				(type default)
			)
			(layer "F.SilkS")
		)
		(fp_line
			(start 0.508 -1.199896)
			(end 1.376172 -1.199896)
			(stroke
				(width 0.1524)
				(type default)
			)
			(layer "F.SilkS")
		)
		(fp_line
			(start 1.376172 -1.199896)
			(end 1.376172 1.199896)
			(stroke
				(width 0.1524)
				(type default)
			)
			(layer "F.SilkS")
		)
		(fp_poly
			(pts
				(xy -1.4605 -0.7493) (xy -2.2225 -1.1303) (xy -2.2225 -0.3683)
			)
			(stroke
				(width 0)
				(type default)
			)
			(fill yes)
			(layer "F.SilkS")
		)
		(fp_line
			(start -0.674878 1.100074)
			(end -0.674878 -1.100074)
			(stroke
				(width 0.1)
				(type default)
			)
			(layer "F.Fab")
		)
		(fp_line
			(start 0.674878 1.100074)
			(end -0.674878 1.100074)
			(stroke
				(width 0.1)
				(type default)
			)
			(layer "F.Fab")
		)
		(fp_line
			(start -0.674878 -1.100074)
			(end 0.674878 -1.100074)
			(stroke
				(width 0.1)
				(type default)
			)
			(layer "F.Fab")
		)
		(fp_line
			(start 0.674878 -1.100074)
			(end 0.674878 1.100074)
			(stroke
				(width 0.1)
				(type default)
			)
			(layer "F.Fab")
		)
		(fp_poly
			(pts
				(xy -1.4605 -0.7493) (xy -2.2225 -1.1303) (xy -2.2225 -0.3683)
			)
			(stroke
				(width 0)
				(type default)
			)
			(fill yes)
			(layer "F.Fab")
		)
		(pad "1" smd rect
			(at -0.899922 -0.750062 180)
			(size 0.6096 0.6096)
			(layers "F.Cu" "F.Mask" "F.Paste")
			(net "GND")
		)
		(pad "2" smd rect
			(at -0.899922 0 180)
			(size 0.4064 0.6096)
			(layers "F.Cu" "F.Mask" "F.Paste")
			(net "H_CPU1_MEMHOT_OUT_R")
		)
		(pad "3" smd rect
			(at -0.899922 0.750062 180)
			(size 0.6096 0.6096)
			(layers "F.Cu" "F.Mask" "F.Paste")
			(net "H_CPU1_MEMHOT_OUT")
		)
		(pad "4" smd rect
			(at 0.899922 0.750062 180)
			(size 0.6096 0.6096)
			(layers "F.Cu" "F.Mask" "F.Paste")
			(net "PVNN_TERM_CPU1")
		)
		(pad "5" smd rect
			(at 0.899922 0 180)
			(size 0.4064 0.6096)
			(layers "F.Cu" "F.Mask" "F.Paste")
			(net "H_CPU1_MEMHOT_OUT_VT_R_N")
		)
		(pad "6" smd rect
			(at 0.899922 -0.750062 180)
			(size 0.6096 0.6096)
			(layers "F.Cu" "F.Mask" "F.Paste")
			(net "H_CPU1_MEMHOT_OUT_VT_N")
		)
	)
	(footprint ""
		(layer "F.Cu")
		(at 176.6824 -94.338648 90)
		(property "Reference" "R4588"
			(at 0 0 90)
			(layer "F.SilkS")
			(hide yes)
			(effects
				(font
					(size 1.27 1.27)
				)
			)
		)
		(property "Value" ""
			(at 0 0 90)
			(layer "F.Fab")
			(effects
				(font
					(size 1.27 1.27)
				)
			)
		)
		(duplicate_pad_numbers_are_jumpers no)
		(fp_line
			(start 0.7874 -0.4064)
			(end 0.7874 0.4064)
			(stroke
				(width 0.1524)
				(type default)
			)
			(layer "F.SilkS")
		)
		(fp_line
			(start -0.7874 -0.4064)
			(end 0.7874 -0.4064)
			(stroke
				(width 0.1524)
				(type default)
			)
			(layer "F.SilkS")
		)
		(fp_line
			(start 0.7874 0.4064)
			(end -0.7874 0.4064)
			(stroke
				(width 0.1524)
				(type default)
			)
			(layer "F.SilkS")
		)
		(fp_line
			(start -0.7874 0.4064)
			(end -0.7874 -0.4064)
			(stroke
				(width 0.1524)
				(type default)
			)
			(layer "F.SilkS")
		)
		(fp_line
			(start -0.12065 -0.305054)
			(end -0.12065 -0.2794)
			(stroke
				(width 0.1)
				(type default)
			)
			(layer "F.Fab")
		)
		(fp_line
			(start -0.67945 -0.305054)
			(end -0.12065 -0.305054)
			(stroke
				(width 0.1)
				(type default)
			)
			(layer "F.Fab")
		)
		(fp_line
			(start 0.67945 -0.3048)
			(end 0.67945 0.3048)
			(stroke
				(width 0.1)
				(type default)
			)
			(layer "F.Fab")
		)
		(fp_line
			(start 0.12065 -0.3048)
			(end 0.67945 -0.3048)
			(stroke
				(width 0.1)
				(type default)
			)
			(layer "F.Fab")
		)
		(fp_line
			(start 0.12065 -0.2794)
			(end 0.12065 -0.3048)
			(stroke
				(width 0.1)
				(type default)
			)
			(layer "F.Fab")
		)
		(fp_line
			(start -0.12065 -0.2794)
			(end 0.12065 -0.2794)
			(stroke
				(width 0.1)
				(type default)
			)
			(layer "F.Fab")
		)
		(fp_line
			(start 0.120396 0.2794)
			(end -0.12065 0.2794)
			(stroke
				(width 0.1)
				(type default)
			)
			(layer "F.Fab")
		)
		(fp_line
			(start -0.12065 0.2794)
			(end -0.12065 0.3048)
			(stroke
				(width 0.1)
				(type default)
			)
			(layer "F.Fab")
		)
		(fp_line
			(start 0.67945 0.3048)
			(end 0.120396 0.3048)
			(stroke
				(width 0.1)
				(type default)
			)
			(layer "F.Fab")
		)
		(fp_line
			(start 0.120396 0.3048)
			(end 0.120396 0.2794)
			(stroke
				(width 0.1)
				(type default)
			)
			(layer "F.Fab")
		)
		(fp_line
			(start -0.12065 0.3048)
			(end -0.67945 0.3048)
			(stroke
				(width 0.1)
				(type default)
			)
			(layer "F.Fab")
		)
		(fp_line
			(start -0.67945 0.3048)
			(end -0.67945 -0.305054)
			(stroke
				(width 0.1)
				(type default)
			)
			(layer "F.Fab")
		)
		(pad "1" smd rect
			(at -0.40005 0 270)
			(size 0.4572 0.508)
			(layers "F.Cu" "F.Mask" "F.Paste")
			(net "FAB_BMC_REV_ID2")
		)
		(pad "2" smd rect
			(at 0.40005 0 270)
			(size 0.4572 0.508)
			(layers "F.Cu" "F.Mask" "F.Paste")
			(net "GND")
		)
	)
)
